# S9S_MB_2U (Grand Teton) — schematic netlist excerpt (pin names and nets, part order shuffled) for the footprints in the layout excerpt that follows; sources: Cadence DE-HDL packaged netlist, KiCad conversion of 03242023_DA0F0TMBIJ0_F0T_Motherboard_J_brd_V01_OCP.brd

U13  9SQ440NQQI8  IC  pkg QFN100_TH_0-5_8X8  page 208
  \25mpg\  = FM_CK440Q_DEV_25M_EN
  \25m1#\  = CLK_25M_CK440_CPU1_DN
  \25m1\  = CLK_25M_CK440_CPU1_DP
  \25m0#\  = CLK_25M_CK440_CPU0_DN
  \25m0\  = CLK_25M_CK440_CPU0_DP
  PFT_OUT  = TP_CLK_CK440_PFT_OUT_DP
  \pft_out#\  = TP_CLK_CK440_PFT_OUT_DN
  PFT_IN  = TP_CLK_PFT_IN_DP
  \pft_in#\  = TP_CLK_PFT_IN_DN
  SCLK  = SMB_HOST_CLK_3V3AUX_SCL
  SMB_ADR0_TRI  = CLK_CK440_SMB_ADDR0
  VDDXTAL  = P3V3_AUX_CLK_GEN_VDDXTAL_CK440
  XIN_CLKIN  = XTAL_CLK_GEN1_25M_X1
  GNDXTAL  = GND
  NC_A15  = NC_CK440_A15
  SS_EN_TRI  = FM_CLK_CK440_SS_EN
  \pwrgd||pwrdn#\  = FM_PLD_CLKS_DEV_EN
  \100m6#\  = NC_CLK_CK440_100M6_DN
  \100m6\  = NC_CLK_CK440_100M6_DP
  \100m5#\  = NC_CLK_CK440_100M5_DN
  \100m5\  = NC_CLK_CK440_100M5_DP
  \100m4#\  = NC_CLK_CK440_100M4_DN
  \100m4\  = NC_CLK_CK440_100M4_DP
  \100m3#\  = NC_CLK_CK440_100M3_DN
  \100m3\  = NC_CLK_CK440_100M3_DP
  \oe3#\  = CK440Q_OE_3
  \100m2#\  = NC_CLK_CK440_100M2_DN
  \100m2\  = NC_CLK_CK440_100M2_DP
  \oe2#\  = CK440Q_OE_2
  \oe1#\  = CK440Q_OE_1
  \100m1#\  = NC_CLK_CK440_100M1_DN
  \100m1\  = NC_CLK_CK440_100M1_DP
  \100m0#\  = CLK_100M_DB2000_DN
  \100m0\  = CLK_100M_DB2000_DP
  \mxck8#\  = NC_CLK_CK440_MXCK8_DN
  MXCK8  = NC_CLK_CK440_MXCK8_DP
  \mxck7#\  = NC_CLK_CK440_MXCK7_DN
  MXCK7  = NC_CLK_CK440_MXCK7_DP
  \mxck6#\  = NC_CLK_CK440_MXCK6_DN
  MXCK6  = NC_CLK_CK440_MXCK6_DP
  \mxck5#\  = NC_CLK_CK440_MXCK5_DN
  MXCK5  = NC_CLK_CK440_MXCK5_DP
  \mxck4#\  = NC_CLK_CK440_MXCK4_DN
  MXCK4  = NC_CLK_CK440_MXCK4_DP
  \mxck3#\  = NC_CLK_CK440_MXCK3_DN
  MXCK3  = NC_CLK_CK440_MXCK3_DP
  \mxck2#\  = CLK_100M_CK440_PCH_EXTCLK_R_DN
  MXCK2  = CLK_100M_CK440_PCH_EXTCLK_R_DP
  \mxck1#\  = NC_CLK_CK440_MXCK1_DN
  MXCK1  = NC_CLK_CK440_MXCK1_DP
  \mxck0#\  = NC_CLK_CK440_MXCK0_DN
  MXCK0  = NC_CLK_CK440_MXCK0_DP
  SBI_OUT  = TP_CK440_SBI_DATA_OUT
  SBI_CLK  = PD_CK440_SBI_CLK
  \25m2#\  = CLK_25M_CK440_ISCLK_REF_DN
  \25m2\  = CLK_25M_CK440_ISCLK_REF_DP
  VDDA25M  = P3V3_AUX_CLK_GEN_VDDA25M_CK440
  NC_B2  = NC_CK440_B2
  NC_B3  = NC_CK440_B3
  \pft_lost#\  = PU_CLK_PFT_LOST_N
  NC_B5  = NC_CK440_B5
  VDDPT  = P3V3_AUX_CLK_GEN_VDDPT_CK440
  NC_B7  = NC_CK440_B7
  SMBDATTA  = SMB_HOST_CLK_3V3AUX_SDA
  SMB_ADR1_TRI  = CLK_CK440_SMB_ADDR1
  GNDS  = GND
  XOUT  = XTAL_CLK_GEN1_25M_X2
  NVGND  = GND
  NC_B13  = NC_CK440_B13
  \oe6#\  = CK440Q_OE_6
  \oe5#\  = CK440Q_OE_5
  NC_B16  = NC_CK440_B16
  VDDA100M  = P3V3_AUX_CLK_GEN_VDDA100M_CK440
  NC_B18  = NC_CK440_B18
  \oe4#\  = CK440Q_OE_4
  NC_B20  = NC_CK440_B20
  VDD100M_B21  = P3V3_AUX_CLK_GEN_VDD_CK440
  NC_B22  = NC_CK440_B22
  VDD100M_B23  = P3V3_AUX_CLK_GEN_VDD_CK440
  NC_B24  = NC_CK440_B24
  NC_B25  = NC_CK440_B25
  NC_B26  = NC_CK440_B26
  \oe0#\  = FM_CLK_GEN1_OE0_N
  NC_B28  = NC_CK440_B28
  VDDMXCK_B29  = P3V3_AUX_CLK_GEN_VDDMXCK_CK440
  NC_B30  = NC_CK440_B30
  NC_B31  = NC_CK440_B31
  VDDMXCK_B32  = P3V3_AUX_CLK_GEN_VDDMXCK_CK440
  NC_B33  = NC_CK440_B33
  NC_B34  = NC_CK440_B34
  VDDMXCK_B35  = P3V3_AUX_CLK_GEN_VDDMXCK_CK440
  NC_B36  = NC_CK440_B36
  NC_B37  = NC_CK440_B37
  \mxck_sel_100m#\  = FM_CK440_MXCK_25M_100M
  NC_B39  = NC_CK440_B39
  VDDMXCK_B40  = P3V3_AUX_CLK_GEN_VDDMXCK_CK440
  NC_B41  = NC_CK440_B41
  \shft_ld#\  = PU_CK440_SHFT_LD_N
  SBI_IN  = PD_CK440_SBI_DATA_IN
  NC_B44  = NC_CK440_B44
  EPAD  = GND

(kicad_pcb
	(version 20260206)
	(generator "pcbnew")
	(generator_version "10.0")
	(general
		(thickness 1.6)
		(legacy_teardrops no)
	)
	(paper "A4")
	(title_block
		(title "03242023_DA0F0TMBIJ0_F0T_Motherboard_J_brd_V01_OCP.brd")
		(comment 1 "Grand Teton / footprint 1793 of 6105 (U13), pads 44-87 of 101")
	)
	(layers
		(0 "F.Cu" signal "TOP")
		(4 "In1.Cu" signal "GND")
		(6 "In2.Cu" signal "IN1")
		(8 "In3.Cu" signal "GND1")
		(10 "In4.Cu" signal "IN2")
		(12 "In5.Cu" signal "GND2")
		(14 "In6.Cu" signal "IN3")
		(16 "In7.Cu" signal "GND3")
		(18 "In8.Cu" signal "VCC")
		(20 "In9.Cu" signal "VCC1")
		(22 "In10.Cu" signal "GND4")
		(24 "In11.Cu" signal "IN4")
		(26 "In12.Cu" signal "GND5")
		(28 "In13.Cu" signal "IN5")
		(30 "In14.Cu" signal "GND6")
		(32 "In15.Cu" signal "IN6")
		(34 "In16.Cu" signal "GND7")
		(2 "B.Cu" signal "BOTTOM")
		(9 "F.Adhes" user "F.Adhesive")
		(11 "B.Adhes" user "B.Adhesive")
		(13 "F.Paste" user "Package Geometry/Pastemask Top")
		(15 "B.Paste" user "Package Geometry/Pastemask Bottom")
		(5 "F.SilkS" user "Ref Des/Silkscreen Top")
		(7 "B.SilkS" user "Ref Des/Silkscreen Bottom")
		(1 "F.Mask" user "Board Geometry/Soldermask Top")
		(3 "B.Mask" user "Board Geometry/Soldermask Bottom")
		(17 "Dwgs.User" user "User.Drawings")
		(19 "Cmts.User" user "User.Comments")
		(21 "Eco1.User" user "User.Eco1")
		(23 "Eco2.User" user "User.Eco2")
		(25 "Edge.Cuts" user "Board Geometry/Outline")
		(27 "Margin" user)
		(31 "F.CrtYd" user "Package Geometry/Place Bound Top")
		(29 "B.CrtYd" user "Package Geometry/Place Bound Bottom")
		(35 "F.Fab" user "Ref Des/Assembly Top")
		(33 "B.Fab" user "Ref Des/Assembly Bottom")
	)
	(footprint ""
		(layer "F.Cu")
		(at 255.68275 -99.563174)
		(property "Reference" "U13"
			(at 3.232404 -8.016748 0)
			(unlocked yes)
			(layer "F.SilkS")
			(effects
				(font
					(size 0.7874 0.5842)
					(thickness 0.1524)
				)
				(justify left)
			)
		)
		(property "Value" ""
			(at 0 0 0)
			(layer "F.Fab")
			(effects
				(font
					(size 1.27 1.27)
				)
			)
		)
		(duplicate_pad_numbers_are_jumpers no)
		(pad "A44" smd rect
			(at 2.750058 -3.875024)
			(size 0.1778 0.5588)
			(layers "F.Cu" "F.Mask" "F.Paste")
			(net "NC_CLK_CK440_MXCK4_DP")
		)
		(pad "A45" smd rect
			(at 2.249932 -3.875024)
			(size 0.1778 0.5588)
			(layers "F.Cu" "F.Mask" "F.Paste")
			(net "NC_CLK_CK440_MXCK3_DN")
		)
		(pad "A46" smd rect
			(at 1.75006 -3.875024)
			(size 0.1778 0.5588)
			(layers "F.Cu" "F.Mask" "F.Paste")
			(net "NC_CLK_CK440_MXCK3_DP")
		)
		(pad "A47" smd rect
			(at 1.249934 -3.875024)
			(size 0.1778 0.5588)
			(layers "F.Cu" "F.Mask" "F.Paste")
			(net "CLK_100M_CK440_PCH_EXTCLK_R_DN")
		)
		(pad "A48" smd rect
			(at 0.750062 -3.875024)
			(size 0.1778 0.5588)
			(layers "F.Cu" "F.Mask" "F.Paste")
			(net "CLK_100M_CK440_PCH_EXTCLK_R_DP")
		)
		(pad "A49" smd rect
			(at 0.249936 -3.875024)
			(size 0.1778 0.5588)
			(layers "F.Cu" "F.Mask" "F.Paste")
			(net "NC_CLK_CK440_MXCK1_DN")
		)
		(pad "A50" smd rect
			(at -0.249936 -3.875024)
			(size 0.1778 0.5588)
			(layers "F.Cu" "F.Mask" "F.Paste")
			(net "NC_CLK_CK440_MXCK1_DP")
		)
		(pad "A51" smd rect
			(at -0.750062 -3.875024)
			(size 0.1778 0.5588)
			(layers "F.Cu" "F.Mask" "F.Paste")
			(net "NC_CLK_CK440_MXCK0_DN")
		)
		(pad "A52" smd rect
			(at -1.249934 -3.875024)
			(size 0.1778 0.5588)
			(layers "F.Cu" "F.Mask" "F.Paste")
			(net "NC_CLK_CK440_MXCK0_DP")
		)
		(pad "A53" smd rect
			(at -1.75006 -3.875024)
			(size 0.1778 0.5588)
			(layers "F.Cu" "F.Mask" "F.Paste")
			(net "TP_CK440_SBI_DATA_OUT")
		)
		(pad "A54" smd rect
			(at -2.249932 -3.875024)
			(size 0.1778 0.5588)
			(layers "F.Cu" "F.Mask" "F.Paste")
			(net "PD_CK440_SBI_CLK")
		)
		(pad "A55" smd rect
			(at -2.750058 -3.875024)
			(size 0.1778 0.5588)
			(layers "F.Cu" "F.Mask" "F.Paste")
			(net "CLK_25M_CK440_ISCLK_REF_DN")
		)
		(pad "A56" smd rect
			(at -3.24993 -3.875024)
			(size 0.1778 0.5588)
			(layers "F.Cu" "F.Mask" "F.Paste")
			(net "CLK_25M_CK440_ISCLK_REF_DP")
		)
		(pad "B1" smd rect
			(at -3.124962 -2.500122 90)
			(size 0.2794 0.4572)
			(layers "F.Cu" "F.Mask" "F.Paste")
			(net "P3V3_AUX_CLK_GEN_VDDA25M_CK440")
		)
		(pad "B2" smd rect
			(at -3.124962 -1.999996 90)
			(size 0.2794 0.4572)
			(layers "F.Cu" "F.Mask" "F.Paste")
			(net "NC_CK440_B2")
		)
		(pad "B3" smd rect
			(at -3.124962 -1.500124 90)
			(size 0.2794 0.4572)
			(layers "F.Cu" "F.Mask" "F.Paste")
			(net "NC_CK440_B3")
		)
		(pad "B4" smd rect
			(at -3.124962 -0.999998 90)
			(size 0.2794 0.4572)
			(layers "F.Cu" "F.Mask" "F.Paste")
			(net "PU_CLK_PFT_LOST_N")
		)
		(pad "B5" smd rect
			(at -3.124962 -0.499872 90)
			(size 0.2794 0.4572)
			(layers "F.Cu" "F.Mask" "F.Paste")
			(net "NC_CK440_B5")
		)
		(pad "B6" smd rect
			(at -3.124962 0 90)
			(size 0.2794 0.4572)
			(layers "F.Cu" "F.Mask" "F.Paste")
			(net "P3V3_AUX_CLK_GEN_VDDPT_CK440")
		)
		(pad "B7" smd rect
			(at -3.124962 0.499872 90)
			(size 0.2794 0.4572)
			(layers "F.Cu" "F.Mask" "F.Paste")
			(net "NC_CK440_B7")
		)
		(pad "B8" smd rect
			(at -3.124962 0.999998 90)
			(size 0.2794 0.4572)
			(layers "F.Cu" "F.Mask" "F.Paste")
			(net "SMB_HOST_CLK_3V3AUX_SDA")
		)
		(pad "B9" smd rect
			(at -3.124962 1.500124 90)
			(size 0.2794 0.4572)
			(layers "F.Cu" "F.Mask" "F.Paste")
			(net "CLK_CK440_SMB_ADDR1")
		)
		(pad "B10" smd rect
			(at -3.124962 1.999996 90)
			(size 0.2794 0.4572)
			(layers "F.Cu" "F.Mask" "F.Paste")
			(net "GND")
		)
		(pad "B11" smd rect
			(at -3.124962 2.500122 90)
			(size 0.2794 0.4572)
			(layers "F.Cu" "F.Mask" "F.Paste")
			(net "XTAL_CLK_GEN1_25M_X2")
		)
		(pad "B12" smd rect
			(at -2.500122 3.124962)
			(size 0.2794 0.4572)
			(layers "F.Cu" "F.Mask" "F.Paste")
			(net "GND")
		)
		(pad "B13" smd rect
			(at -1.999996 3.124962)
			(size 0.2794 0.4572)
			(layers "F.Cu" "F.Mask" "F.Paste")
			(net "NC_CK440_B13")
		)
		(pad "B14" smd rect
			(at -1.500124 3.124962)
			(size 0.2794 0.4572)
			(layers "F.Cu" "F.Mask" "F.Paste")
			(net "CK440Q_OE_6")
		)
		(pad "B15" smd rect
			(at -0.999998 3.124962)
			(size 0.2794 0.4572)
			(layers "F.Cu" "F.Mask" "F.Paste")
			(net "CK440Q_OE_5")
		)
		(pad "B16" smd rect
			(at -0.499872 3.124962)
			(size 0.2794 0.4572)
			(layers "F.Cu" "F.Mask" "F.Paste")
			(net "NC_CK440_B16")
		)
		(pad "B17" smd rect
			(at 0 3.124962)
			(size 0.2794 0.4572)
			(layers "F.Cu" "F.Mask" "F.Paste")
			(net "P3V3_AUX_CLK_GEN_VDDA100M_CK440")
		)
		(pad "B18" smd rect
			(at 0.499872 3.124962)
			(size 0.2794 0.4572)
			(layers "F.Cu" "F.Mask" "F.Paste")
			(net "NC_CK440_B18")
		)
		(pad "B19" smd rect
			(at 0.999998 3.124962)
			(size 0.2794 0.4572)
			(layers "F.Cu" "F.Mask" "F.Paste")
			(net "CK440Q_OE_4")
		)
		(pad "B20" smd rect
			(at 1.500124 3.124962)
			(size 0.2794 0.4572)
			(layers "F.Cu" "F.Mask" "F.Paste")
			(net "NC_CK440_B20")
		)
		(pad "B21" smd rect
			(at 1.999996 3.124962)
			(size 0.2794 0.4572)
			(layers "F.Cu" "F.Mask" "F.Paste")
			(net "P3V3_AUX_CLK_GEN_VDD_CK440")
		)
		(pad "B22" smd rect
			(at 2.500122 3.124962)
			(size 0.2794 0.4572)
			(layers "F.Cu" "F.Mask" "F.Paste")
			(net "NC_CK440_B22")
		)
		(pad "B23" smd rect
			(at 3.124962 2.500122 270)
			(size 0.2794 0.4572)
			(layers "F.Cu" "F.Mask" "F.Paste")
			(net "P3V3_AUX_CLK_GEN_VDD_CK440")
		)
		(pad "B24" smd rect
			(at 3.124962 1.999996 270)
			(size 0.2794 0.4572)
			(layers "F.Cu" "F.Mask" "F.Paste")
			(net "NC_CK440_B24")
		)
		(pad "B25" smd rect
			(at 3.124962 1.500124 270)
			(size 0.2794 0.4572)
			(layers "F.Cu" "F.Mask" "F.Paste")
			(net "NC_CK440_B25")
		)
		(pad "B26" smd rect
			(at 3.124962 0.999998 270)
			(size 0.2794 0.4572)
			(layers "F.Cu" "F.Mask" "F.Paste")
			(net "NC_CK440_B26")
		)
		(pad "B27" smd rect
			(at 3.124962 0.499872 270)
			(size 0.2794 0.4572)
			(layers "F.Cu" "F.Mask" "F.Paste")
			(net "FM_CLK_GEN1_OE0_N")
		)
		(pad "B28" smd rect
			(at 3.124962 0 270)
			(size 0.2794 0.4572)
			(layers "F.Cu" "F.Mask" "F.Paste")
			(net "NC_CK440_B28")
		)
		(pad "B29" smd rect
			(at 3.124962 -0.499872 270)
			(size 0.2794 0.4572)
			(layers "F.Cu" "F.Mask" "F.Paste")
			(net "P3V3_AUX_CLK_GEN_VDDMXCK_CK440")
		)
		(pad "B30" smd rect
			(at 3.124962 -0.999998 270)
			(size 0.2794 0.4572)
			(layers "F.Cu" "F.Mask" "F.Paste")
			(net "NC_CK440_B30")
		)
		(pad "B31" smd rect
			(at 3.124962 -1.500124 270)
			(size 0.2794 0.4572)
			(layers "F.Cu" "F.Mask" "F.Paste")
			(net "NC_CK440_B31")
		)
	)
)
